(kicad_pcb
	(version 20260206)
	(generator "pcbnew")
	(generator_version "10.0")
	(general
		(thickness 1.6)
		(legacy_teardrops no)
	)
	(paper "A4")
	(title_block
		(title "Wiwynn_Tioga_Pass_MB.brd")
		(comment 1 "Tioga Pass / footprints 2926-2932 of 4770")
	)
	(layers
		(0 "F.Cu" signal "TOP")
		(4 "In1.Cu" signal "L2GND")
		(6 "In2.Cu" signal "L3")
		(8 "In3.Cu" signal "L4GND")
		(10 "In4.Cu" signal "L5")
		(12 "In5.Cu" signal "L6GND")
		(14 "In6.Cu" signal "L7VCC")
		(16 "In7.Cu" signal "L8VCC")
		(18 "In8.Cu" signal "L9GND")
		(20 "In9.Cu" signal "L10")
		(22 "In10.Cu" signal "L11GND")
		(24 "In11.Cu" signal "L12")
		(26 "In12.Cu" signal "L13GND")
		(2 "B.Cu" signal "BOTTOM")
		(9 "F.Adhes" user "F.Adhesive")
		(11 "B.Adhes" user "B.Adhesive")
		(13 "F.Paste" user "Package Geometry/Pastemask Top")
		(15 "B.Paste" user "Package Geometry/Pastemask Bottom")
		(5 "F.SilkS" user "Ref Des/Silkscreen Top")
		(7 "B.SilkS" user "Ref Des/Silkscreen Bottom")
		(1 "F.Mask" user "Board Geometry/Soldermask Top")
		(3 "B.Mask" user "Board Geometry/Soldermask Bottom")
		(17 "Dwgs.User" user "User.Drawings")
		(19 "Cmts.User" user "User.Comments")
		(21 "Eco1.User" user "User.Eco1")
		(23 "Eco2.User" user "User.Eco2")
		(25 "Edge.Cuts" user "Board Geometry/Outline")
		(27 "Margin" user)
		(31 "F.CrtYd" user "Package Geometry/Place Bound Top")
		(29 "B.CrtYd" user "Package Geometry/Place Bound Bottom")
		(35 "F.Fab" user "Ref Des/Assembly Top")
		(33 "B.Fab" user "Ref Des/Assembly Bottom")
	)
	(footprint ""
		(layer "B.Cu")
		(at 340.741 -84.5058 90)
		(property "Reference" "R3P18"
			(at 0 0 90)
			(layer "B.SilkS")
			(hide yes)
			(effects
				(font
					(size 1.27 1.27)
				)
				(justify mirror)
			)
		)
		(property "Value" ""
			(at 0 0 90)
			(layer "B.Fab")
			(effects
				(font
					(size 1.27 1.27)
				)
				(justify mirror)
			)
		)
		(duplicate_pad_numbers_are_jumpers no)
		(fp_poly
			(pts
				(xy 0.2794 -0.1016) (xy -0.2794 -0.1016) (xy -0.2794 0.9906) (xy 0.2794 0.9906)
			)
			(stroke
				(width 0)
				(type default)
			)
			(fill no)
			(layer "B.CrtYd")
		)
		(fp_line
			(start 0.2794 -0.1016)
			(end 0.2794 0.9906)
			(stroke
				(width 0.1)
				(type default)
			)
			(layer "B.Fab")
		)
		(fp_line
			(start -0.2794 -0.1016)
			(end 0.2794 -0.1016)
			(stroke
				(width 0.1)
				(type default)
			)
			(layer "B.Fab")
		)
		(fp_line
			(start 0.2794 0.9906)
			(end -0.2794 0.9906)
			(stroke
				(width 0.1)
				(type default)
			)
			(layer "B.Fab")
		)
		(fp_line
			(start -0.2794 0.9906)
			(end -0.2794 -0.1016)
			(stroke
				(width 0.1)
				(type default)
			)
			(layer "B.Fab")
		)
		(pad "1" smd rect
			(at 0 0 270)
			(size 0.508 0.508)
			(layers "B.Cu" "B.Mask" "B.Paste")
			(net "P3V3_STBY")
		)
		(pad "2" smd rect
			(at 0 0.889 270)
			(size 0.508 0.508)
			(layers "B.Cu" "B.Mask" "B.Paste")
			(net "IRQ_PVCCIO_CPU0_VRHOT_N")
		)
		(zone
			(layer "B.Cu")
			(hatch none 0.5)
			(connect_pads
				(clearance 0)
			)
			(min_thickness 0.25)
			(keepout
				(tracks allowed)
				(vias not_allowed)
				(pads allowed)
				(copperpour not_allowed)
				(footprints allowed)
			)
			(placement
				(enabled no)
				(sheetname "")
			)
			(fill
				(thermal_gap 0.5)
				(thermal_bridge_width 0.5)
				(island_removal_mode 0)
			)
			(polygon
				(pts
					(xy 340.995 -84.7598) (xy 340.995 -84.2518) (xy 341.376 -84.2518) (xy 341.376 -84.7598)
				)
			)
		)
		(zone
			(layer "B.Cu")
			(hatch none 0.5)
			(connect_pads
				(clearance 0)
			)
			(min_thickness 0.25)
			(keepout
				(tracks not_allowed)
				(vias allowed)
				(pads allowed)
				(copperpour not_allowed)
				(footprints allowed)
			)
			(placement
				(enabled no)
				(sheetname "")
			)
			(fill
				(thermal_gap 0.5)
				(thermal_bridge_width 0.5)
				(island_removal_mode 0)
			)
			(polygon
				(pts
					(xy 341.376 -84.7598) (xy 341.376 -84.2518) (xy 340.995 -84.2518) (xy 340.995 -84.7598)
				)
			)
		)
	)
	(footprint ""
		(layer "B.Cu")
		(at 164.973 -68.199 -90)
		(property "Reference" "R6P35"
			(at 0 0 90)
			(layer "B.SilkS")
			(hide yes)
			(effects
				(font
					(size 1.27 1.27)
				)
				(justify mirror)
			)
		)
		(property "Value" ""
			(at 0 0 90)
			(layer "B.Fab")
			(effects
				(font
					(size 1.27 1.27)
				)
				(justify mirror)
			)
		)
		(duplicate_pad_numbers_are_jumpers no)
		(fp_poly
			(pts
				(xy 0.2794 -0.1016) (xy -0.2794 -0.1016) (xy -0.2794 0.9906) (xy 0.2794 0.9906)
			)
			(stroke
				(width 0)
				(type default)
			)
			(fill no)
			(layer "B.CrtYd")
		)
		(fp_line
			(start -0.2794 0.9906)
			(end -0.2794 -0.1016)
			(stroke
				(width 0.1)
				(type default)
			)
			(layer "B.Fab")
		)
		(fp_line
			(start 0.2794 0.9906)
			(end -0.2794 0.9906)
			(stroke
				(width 0.1)
				(type default)
			)
			(layer "B.Fab")
		)
		(fp_line
			(start -0.2794 -0.1016)
			(end 0.2794 -0.1016)
			(stroke
				(width 0.1)
				(type default)
			)
			(layer "B.Fab")
		)
		(fp_line
			(start 0.2794 -0.1016)
			(end 0.2794 0.9906)
			(stroke
				(width 0.1)
				(type default)
			)
			(layer "B.Fab")
		)
		(pad "1" smd rect
			(at 0 0 90)
			(size 0.508 0.508)
			(layers "B.Cu" "B.Mask" "B.Paste")
			(net "PVCCIO_CPU1")
		)
		(pad "2" smd rect
			(at 0 0.889 90)
			(size 0.508 0.508)
			(layers "B.Cu" "B.Mask" "B.Paste")
			(net "SVID_DIO0_CPU1_R")
		)
		(zone
			(layer "B.Cu")
			(hatch none 0.5)
			(connect_pads
				(clearance 0)
			)
			(min_thickness 0.25)
			(keepout
				(tracks not_allowed)
				(vias allowed)
				(pads allowed)
				(copperpour not_allowed)
				(footprints allowed)
			)
			(placement
				(enabled no)
				(sheetname "")
			)
			(fill
				(thermal_gap 0.5)
				(thermal_bridge_width 0.5)
				(island_removal_mode 0)
			)
			(polygon
				(pts
					(xy 164.338 -67.945) (xy 164.338 -68.453) (xy 164.719 -68.453) (xy 164.719 -67.945)
				)
			)
		)
		(zone
			(layer "B.Cu")
			(hatch none 0.5)
			(connect_pads
				(clearance 0)
			)
			(min_thickness 0.25)
			(keepout
				(tracks allowed)
				(vias not_allowed)
				(pads allowed)
				(copperpour not_allowed)
				(footprints allowed)
			)
			(placement
				(enabled no)
				(sheetname "")
			)
			(fill
				(thermal_gap 0.5)
				(thermal_bridge_width 0.5)
				(island_removal_mode 0)
			)
			(polygon
				(pts
					(xy 164.719 -67.945) (xy 164.719 -68.453) (xy 164.338 -68.453) (xy 164.338 -67.945)
				)
			)
		)
	)
	(footprint ""
		(layer "B.Cu")
		(at 248.8565 -3.3528 -90)
		(property "Reference" "C5G51"
			(at -1.14681 0.76708 0)
			(unlocked yes)
			(layer "B.SilkS")
			(effects
				(font
					(size 0.7874 0.5842)
					(thickness 0.1524)
				)
				(justify mirror)
			)
		)
		(property "Value" ""
			(at 0 0 90)
			(layer "B.Fab")
			(effects
				(font
					(size 1.27 1.27)
				)
				(justify mirror)
			)
		)
		(duplicate_pad_numbers_are_jumpers no)
		(fp_rect
			(start 0.4953 1.6002)
			(end -0.4953 -0.2032)
			(stroke
				(width 0)
				(type default)
			)
			(fill no)
			(layer "B.CrtYd")
		)
		(fp_line
			(start -0.4953 1.6002)
			(end 0.4953 1.6002)
			(stroke
				(width 0.1)
				(type default)
			)
			(layer "B.Fab")
		)
		(fp_line
			(start 0.4953 1.6002)
			(end 0.4953 -0.2032)
			(stroke
				(width 0.1)
				(type default)
			)
			(layer "B.Fab")
		)
		(fp_line
			(start -0.4953 -0.2032)
			(end -0.4953 1.6002)
			(stroke
				(width 0.1)
				(type default)
			)
			(layer "B.Fab")
		)
		(fp_line
			(start 0.4953 -0.2032)
			(end -0.4953 -0.2032)
			(stroke
				(width 0.1)
				(type default)
			)
			(layer "B.Fab")
		)
		(pad "1" smd rect
			(at 0 0 90)
			(size 0.762 0.889)
			(layers "B.Cu" "B.Mask" "B.Paste")
			(net "PVDDQ_ABC")
		)
		(pad "2" smd rect
			(at 0 1.397 90)
			(size 0.762 0.889)
			(layers "B.Cu" "B.Mask" "B.Paste")
			(net "GND")
		)
		(zone
			(layer "B.Cu")
			(hatch none 0.5)
			(connect_pads
				(clearance 0)
			)
			(min_thickness 0.25)
			(keepout
				(tracks not_allowed)
				(vias allowed)
				(pads allowed)
				(copperpour not_allowed)
				(footprints allowed)
			)
			(placement
				(enabled no)
				(sheetname "")
			)
			(fill
				(thermal_gap 0.5)
				(thermal_bridge_width 0.5)
				(island_removal_mode 0)
			)
			(polygon
				(pts
					(xy 247.904 -2.9718) (xy 248.412 -2.9718) (xy 248.412 -3.7338) (xy 247.904 -3.7338)
				)
			)
		)
	)
	(footprint ""
		(layer "B.Cu")
		(at 471.9447 -128.39954 -90)
		(property "Reference" "R1M23"
			(at 0 0 90)
			(layer "B.SilkS")
			(hide yes)
			(effects
				(font
					(size 1.27 1.27)
				)
				(justify mirror)
			)
		)
		(property "Value" ""
			(at 0 0 90)
			(layer "B.Fab")
			(effects
				(font
					(size 1.27 1.27)
				)
				(justify mirror)
			)
		)
		(duplicate_pad_numbers_are_jumpers no)
		(fp_poly
			(pts
				(xy 0.2794 -0.1016) (xy -0.2794 -0.1016) (xy -0.2794 0.9906) (xy 0.2794 0.9906)
			)
			(stroke
				(width 0)
				(type default)
			)
			(fill no)
			(layer "B.CrtYd")
		)
		(fp_line
			(start -0.2794 0.9906)
			(end -0.2794 -0.1016)
			(stroke
				(width 0.1)
				(type default)
			)
			(layer "B.Fab")
		)
		(fp_line
			(start 0.2794 0.9906)
			(end -0.2794 0.9906)
			(stroke
				(width 0.1)
				(type default)
			)
			(layer "B.Fab")
		)
		(fp_line
			(start -0.2794 -0.1016)
			(end 0.2794 -0.1016)
			(stroke
				(width 0.1)
				(type default)
			)
			(layer "B.Fab")
		)
		(fp_line
			(start 0.2794 -0.1016)
			(end 0.2794 0.9906)
			(stroke
				(width 0.1)
				(type default)
			)
			(layer "B.Fab")
		)
		(pad "1" smd rect
			(at 0 0 90)
			(size 0.508 0.508)
			(layers "B.Cu" "B.Mask" "B.Paste")
			(net "JTAG_MCP_TRST_N")
		)
		(pad "2" smd rect
			(at 0 0.889 90)
			(size 0.508 0.508)
			(layers "B.Cu" "B.Mask" "B.Paste")
			(net "GND")
		)
		(zone
			(layer "B.Cu")
			(hatch none 0.5)
			(connect_pads
				(clearance 0)
			)
			(min_thickness 0.25)
			(keepout
				(tracks not_allowed)
				(vias allowed)
				(pads allowed)
				(copperpour not_allowed)
				(footprints allowed)
			)
			(placement
				(enabled no)
				(sheetname "")
			)
			(fill
				(thermal_gap 0.5)
				(thermal_bridge_width 0.5)
				(island_removal_mode 0)
			)
			(polygon
				(pts
					(xy 471.3097 -128.14554) (xy 471.3097 -128.65354) (xy 471.6907 -128.65354) (xy 471.6907 -128.14554)
				)
			)
		)
		(zone
			(layer "B.Cu")
			(hatch none 0.5)
			(connect_pads
				(clearance 0)
			)
			(min_thickness 0.25)
			(keepout
				(tracks allowed)
				(vias not_allowed)
				(pads allowed)
				(copperpour not_allowed)
				(footprints allowed)
			)
			(placement
				(enabled no)
				(sheetname "")
			)
			(fill
				(thermal_gap 0.5)
				(thermal_bridge_width 0.5)
				(island_removal_mode 0)
			)
			(polygon
				(pts
					(xy 471.6907 -128.14554) (xy 471.6907 -128.65354) (xy 471.3097 -128.65354) (xy 471.3097 -128.14554)
				)
			)
		)
	)
	(footprint ""
		(layer "B.Cu")
		(at 417.232846 -44.650152 180)
		(property "Reference" "R25W63"
			(at 0.8382 -0.67818 180)
			(unlocked yes)
			(layer "B.SilkS")
			(effects
				(font
					(size 0.4064 0.254)
					(thickness 0.1524)
				)
				(justify left mirror)
			)
		)
		(property "Value" ""
			(at 0 0 0)
			(layer "B.Fab")
			(effects
				(font
					(size 1.27 1.27)
				)
				(justify mirror)
			)
		)
		(duplicate_pad_numbers_are_jumpers no)
		(fp_poly
			(pts
				(xy 0.2794 -0.1016) (xy -0.2794 -0.1016) (xy -0.2794 0.9906) (xy 0.2794 0.9906)
			)
			(stroke
				(width 0)
				(type default)
			)
			(fill no)
			(layer "B.CrtYd")
		)
		(fp_line
			(start 0.2794 0.9906)
			(end -0.2794 0.9906)
			(stroke
				(width 0.1)
				(type default)
			)
			(layer "B.Fab")
		)
		(fp_line
			(start 0.2794 -0.1016)
			(end 0.2794 0.9906)
			(stroke
				(width 0.1)
				(type default)
			)
			(layer "B.Fab")
		)
		(fp_line
			(start -0.2794 0.9906)
			(end -0.2794 -0.1016)
			(stroke
				(width 0.1)
				(type default)
			)
			(layer "B.Fab")
		)
		(fp_line
			(start -0.2794 -0.1016)
			(end 0.2794 -0.1016)
			(stroke
				(width 0.1)
				(type default)
			)
			(layer "B.Fab")
		)
		(pad "1" smd rect
			(at 0 0)
			(size 0.508 0.508)
			(layers "B.Cu" "B.Mask" "B.Paste")
			(net "FM_PE_BMC_WAKE_N")
		)
		(pad "2" smd rect
			(at 0 0.889)
			(size 0.508 0.508)
			(layers "B.Cu" "B.Mask" "B.Paste")
			(net "GND")
		)
		(zone
			(layer "B.Cu")
			(hatch none 0.5)
			(connect_pads
				(clearance 0)
			)
			(min_thickness 0.25)
			(keepout
				(tracks not_allowed)
				(vias allowed)
				(pads allowed)
				(copperpour not_allowed)
				(footprints allowed)
			)
			(placement
				(enabled no)
				(sheetname "")
			)
			(fill
				(thermal_gap 0.5)
				(thermal_bridge_width 0.5)
				(island_removal_mode 0)
			)
			(polygon
				(pts
					(xy 416.978846 -45.285152) (xy 417.486846 -45.285152) (xy 417.486846 -44.904152) (xy 416.978846 -44.904152)
				)
			)
		)
		(zone
			(layer "B.Cu")
			(hatch none 0.5)
			(connect_pads
				(clearance 0)
			)
			(min_thickness 0.25)
			(keepout
				(tracks allowed)
				(vias not_allowed)
				(pads allowed)
				(copperpour not_allowed)
				(footprints allowed)
			)
			(placement
				(enabled no)
				(sheetname "")
			)
			(fill
				(thermal_gap 0.5)
				(thermal_bridge_width 0.5)
				(island_removal_mode 0)
			)
			(polygon
				(pts
					(xy 416.978846 -44.904152) (xy 417.486846 -44.904152) (xy 417.486846 -45.285152) (xy 416.978846 -45.285152)
				)
			)
		)
	)
	(footprint ""
		(layer "B.Cu")
		(at 348.5896 -153.8732 -90)
		(property "Reference" "C3L2"
			(at 0 0 90)
			(layer "B.SilkS")
			(hide yes)
			(effects
				(font
					(size 1.27 1.27)
				)
				(justify mirror)
			)
		)
		(property "Value" ""
			(at 0 0 90)
			(layer "B.Fab")
			(effects
				(font
					(size 1.27 1.27)
				)
				(justify mirror)
			)
		)
		(duplicate_pad_numbers_are_jumpers no)
		(fp_poly
			(pts
				(xy 0.7239 -0.2159) (xy -0.7239 -0.2159) (xy -0.7239 1.9939) (xy 0.7239 1.9939)
			)
			(stroke
				(width 0)
				(type default)
			)
			(fill no)
			(layer "B.CrtYd")
		)
		(fp_line
			(start -0.7239 1.9939)
			(end -0.7239 -0.2159)
			(stroke
				(width 0.1)
				(type default)
			)
			(layer "B.Fab")
		)
		(fp_line
			(start 0.7239 1.9939)
			(end -0.7239 1.9939)
			(stroke
				(width 0.1)
				(type default)
			)
			(layer "B.Fab")
		)
		(fp_line
			(start -0.7239 -0.2159)
			(end 0.7239 -0.2159)
			(stroke
				(width 0.1)
				(type default)
			)
			(layer "B.Fab")
		)
		(fp_line
			(start 0.7239 -0.2159)
			(end 0.7239 1.9939)
			(stroke
				(width 0.1)
				(type default)
			)
			(layer "B.Fab")
		)
		(pad "1" smd rect
			(at 0 0 90)
			(size 1.27 1.016)
			(layers "B.Cu" "B.Mask" "B.Paste")
			(net "VR_FET_SW_P12V_STBY_PVDDQ_DEF")
		)
		(pad "2" smd rect
			(at 0 1.778 90)
			(size 1.27 1.016)
			(layers "B.Cu" "B.Mask" "B.Paste")
			(net "GND")
		)
		(zone
			(layer "B.Cu")
			(hatch none 0.5)
			(connect_pads
				(clearance 0)
			)
			(min_thickness 0.25)
			(keepout
				(tracks not_allowed)
				(vias allowed)
				(pads allowed)
				(copperpour not_allowed)
				(footprints allowed)
			)
			(placement
				(enabled no)
				(sheetname "")
			)
			(fill
				(thermal_gap 0.5)
				(thermal_bridge_width 0.5)
				(island_removal_mode 0)
			)
			(polygon
				(pts
					(xy 348.0816 -153.2382) (xy 348.0816 -154.5082) (xy 347.3196 -154.5082) (xy 347.3196 -153.2382)
				)
			)
		)
	)
	(footprint ""
		(layer "B.Cu")
		(at 385.6482 -109.8804 90)
		(property "Reference" "C3N10"
			(at 0 0 90)
			(layer "B.SilkS")
			(hide yes)
			(effects
				(font
					(size 1.27 1.27)
				)
				(justify mirror)
			)
		)
		(property "Value" ""
			(at 0 0 90)
			(layer "B.Fab")
			(effects
				(font
					(size 1.27 1.27)
				)
				(justify mirror)
			)
		)
		(duplicate_pad_numbers_are_jumpers no)
		(fp_rect
			(start 0.499872 1.522476)
			(end -0.500126 -0.277622)
			(stroke
				(width 0)
				(type default)
			)
			(fill no)
			(layer "B.CrtYd")
		)
		(fp_line
			(start 0.499872 -0.277622)
			(end -0.500126 -0.277622)
			(stroke
				(width 0.1)
				(type default)
			)
			(layer "B.Fab")
		)
		(fp_line
			(start -0.500126 -0.277622)
			(end -0.500126 1.522476)
			(stroke
				(width 0.1)
				(type default)
			)
			(layer "B.Fab")
		)
		(fp_line
			(start 0.499872 1.522476)
			(end 0.499872 -0.277622)
			(stroke
				(width 0.1)
				(type default)
			)
			(layer "B.Fab")
		)
		(fp_line
			(start -0.500126 1.522476)
			(end 0.499872 1.522476)
			(stroke
				(width 0.1)
				(type default)
			)
			(layer "B.Fab")
		)
		(pad "1" smd custom
			(at 0 0)
			(size 0.18415 0.18415)
			(layers "B.Cu" "B.Mask" "B.Paste")
			(net "PVNN_PCH_STBY")
			(options
				(clearance outline)
				(anchor circle)
			)
			(primitives
				(gr_poly
					(pts
						(arc
							(start -0.3683 0.2794)
							(mid -0.338542 0.351242)
							(end -0.2667 0.381)
						)
						(arc
							(start 0.2667 0.381)
							(mid 0.338542 0.351242)
							(end 0.3683 0.2794)
						)
						(arc
							(start 0.3683 -0.2794)
							(mid 0.338542 -0.351242)
							(end 0.2667 -0.381)
						)
						(arc
							(start -0.2667 -0.381)
							(mid -0.338542 -0.351242)
							(end -0.3683 -0.2794)
						)
					)
					(width 0)
					(fill yes)
				)
			)
		)
		(pad "2" smd custom
			(at 0 1.2446)
			(size 0.18415 0.18415)
			(layers "B.Cu" "B.Mask" "B.Paste")
			(net "GND")
			(options
				(clearance outline)
				(anchor circle)
			)
			(primitives
				(gr_poly
					(pts
						(arc
							(start -0.3683 0.2794)
							(mid -0.338542 0.351242)
							(end -0.2667 0.381)
						)
						(arc
							(start 0.2667 0.381)
							(mid 0.338542 0.351242)
							(end 0.3683 0.2794)
						)
						(arc
							(start 0.3683 -0.2794)
							(mid 0.338542 -0.351242)
							(end 0.2667 -0.381)
						)
						(arc
							(start -0.2667 -0.381)
							(mid -0.338542 -0.351242)
							(end -0.3683 -0.2794)
						)
					)
					(width 0)
					(fill yes)
				)
			)
		)
		(zone
			(layer "B.Cu")
			(hatch none 0.5)
			(connect_pads
				(clearance 0)
			)
			(min_thickness 0.25)
			(keepout
				(tracks not_allowed)
				(vias allowed)
				(pads allowed)
				(copperpour not_allowed)
				(footprints allowed)
			)
			(placement
				(enabled no)
				(sheetname "")
			)
			(fill
				(thermal_gap 0.5)
				(thermal_bridge_width 0.5)
				(island_removal_mode 0)
			)
			(polygon
				(pts
					(xy 386.5245 -110.2614) (xy 386.0165 -110.2614) (xy 386.0165 -109.4994) (xy 386.5245 -109.4994)
				)
			)
		)
		(zone
			(layer "B.Cu")
			(hatch none 0.5)
			(connect_pads
				(clearance 0)
			)
			(min_thickness 0.25)
			(keepout
				(tracks allowed)
				(vias not_allowed)
				(pads allowed)
				(copperpour not_allowed)
				(footprints allowed)
			)
			(placement
				(enabled no)
				(sheetname "")
			)
			(fill
				(thermal_gap 0.5)
				(thermal_bridge_width 0.5)
				(island_removal_mode 0)
			)
			(polygon
				(pts
					(xy 386.5245 -110.2614) (xy 386.0165 -110.2614) (xy 386.0165 -109.4994) (xy 386.5245 -109.4994)
				)
			)
		)
	)
)
